(kicad_pcb
	(version 20260206)
	(generator "pcbnew")
	(generator_version "10.0")
	(general
		(thickness 1.6)
		(legacy_teardrops no)
	)
	(paper "A4")
	(title_block
		(title "Bryce Canyon_F.DPB_16315-1-OCP.brd")
		(comment 1 "Bryce Canyon / footprints 965-971 of 2223")
	)
	(layers
		(0 "F.Cu" signal "TOP")
		(4 "In1.Cu" signal "L2GND")
		(6 "In2.Cu" signal "L3")
		(8 "In3.Cu" signal "L4GND")
		(10 "In4.Cu" signal "L5")
		(12 "In5.Cu" signal "L6VCC")
		(14 "In6.Cu" signal "L7VCC")
		(16 "In7.Cu" signal "L8")
		(18 "In8.Cu" signal "L9GND")
		(20 "In9.Cu" signal "L10")
		(22 "In10.Cu" signal "L11GND")
		(2 "B.Cu" signal "BOTTOM")
		(9 "F.Adhes" user "F.Adhesive")
		(11 "B.Adhes" user "B.Adhesive")
		(13 "F.Paste" user "Package Geometry/Pastemask Top")
		(15 "B.Paste" user "Package Geometry/Pastemask Bottom")
		(5 "F.SilkS" user "Ref Des/Silkscreen Top")
		(7 "B.SilkS" user "Ref Des/Silkscreen Bottom")
		(1 "F.Mask" user "Board Geometry/Soldermask Top")
		(3 "B.Mask" user "Board Geometry/Soldermask Bottom")
		(17 "Dwgs.User" user "User.Drawings")
		(19 "Cmts.User" user "User.Comments")
		(21 "Eco1.User" user "User.Eco1")
		(23 "Eco2.User" user "User.Eco2")
		(25 "Edge.Cuts" user "Board Geometry/Outline")
		(27 "Margin" user)
		(31 "F.CrtYd" user "Package Geometry/Place Bound Top")
		(29 "B.CrtYd" user "Package Geometry/Place Bound Bottom")
		(35 "F.Fab" user "Ref Des/Assembly Top")
		(33 "B.Fab" user "Ref Des/Assembly Bottom")
	)
	(footprint ""
		(layer "F.Cu")
		(at 69.60997 -298.219368)
		(property "Reference" "Q289"
			(at 0 0 0)
			(layer "F.SilkS")
			(hide yes)
			(effects
				(font
					(size 1.27 1.27)
				)
			)
		)
		(property "Value" "SSM3K324R-GP"
			(at 0.127 -8.9662 0)
			(unlocked yes)
			(layer "F.Fab")
			(hide yes)
			(effects
				(font
					(size 1.016 1.016)
					(thickness 0.1524)
				)
			)
		)
		(property "Device Type" "SOT23DGS2D4H35"
			(at 0.127 -10.4902 0)
			(unlocked yes)
			(layer "F.Fab")
			(hide yes)
			(effects
				(font
					(size 1.016 1.016)
					(thickness 0.1524)
				)
			)
		)
		(duplicate_pad_numbers_are_jumpers no)
		(fp_line
			(start -1.651 -1.778)
			(end -1.651 1.778)
			(stroke
				(width 0.1524)
				(type default)
			)
			(layer "F.SilkS")
		)
		(fp_line
			(start -1.651 1.778)
			(end 1.651 1.778)
			(stroke
				(width 0.1524)
				(type default)
			)
			(layer "F.SilkS")
		)
		(fp_line
			(start 1.651 -1.778)
			(end -1.651 -1.778)
			(stroke
				(width 0.1524)
				(type default)
			)
			(layer "F.SilkS")
		)
		(fp_line
			(start 1.651 1.778)
			(end 1.651 -1.778)
			(stroke
				(width 0.1524)
				(type default)
			)
			(layer "F.SilkS")
		)
		(fp_poly
			(pts
				(xy -1.778 1.8796) (xy -1.778 -1.8796) (xy 1.778 -1.8796) (xy 1.778 1.8796)
			)
			(stroke
				(width 0)
				(type default)
			)
			(fill no)
			(layer "F.CrtYd")
		)
		(fp_poly
			(pts
				(xy -1.778 1.8796) (xy -1.778 -1.8796) (xy 1.778 -1.8796) (xy 1.778 1.8796)
			)
			(stroke
				(width 0)
				(type default)
			)
			(fill no)
			(layer "F.Fab")
		)
		(pad "D" smd custom
			(at 0 -0.9525)
			(size 0.1905 0.1905)
			(layers "F.Cu" "F.Mask" "F.Paste")
			(net "DRV_ACT_26_N")
			(options
				(clearance outline)
				(anchor circle)
			)
			(primitives
				(gr_poly
					(pts
						(arc
							(start -0.1778 0.5715)
							(mid -0.321484 0.511984)
							(end -0.381 0.3683)
						)
						(arc
							(start -0.381 -0.3683)
							(mid -0.321484 -0.511984)
							(end -0.1778 -0.5715)
						)
						(arc
							(start 0.1778 -0.5715)
							(mid 0.321484 -0.511984)
							(end 0.381 -0.3683)
						)
						(arc
							(start 0.381 0.3683)
							(mid 0.321484 0.511984)
							(end 0.1778 0.5715)
						)
					)
					(width 0)
					(fill yes)
				)
			)
		)
		(pad "G" smd custom
			(at -0.98425 0.9525)
			(size 0.1905 0.1905)
			(layers "F.Cu" "F.Mask" "F.Paste")
			(net "DRIVE_B_26_ACT")
			(options
				(clearance outline)
				(anchor circle)
			)
			(primitives
				(gr_poly
					(pts
						(arc
							(start -0.1778 0.5715)
							(mid -0.321484 0.511984)
							(end -0.381 0.3683)
						)
						(arc
							(start -0.381 -0.3683)
							(mid -0.321484 -0.511984)
							(end -0.1778 -0.5715)
						)
						(arc
							(start 0.1778 -0.5715)
							(mid 0.321484 -0.511984)
							(end 0.381 -0.3683)
						)
						(arc
							(start 0.381 0.3683)
							(mid 0.321484 0.511984)
							(end 0.1778 0.5715)
						)
					)
					(width 0)
					(fill yes)
				)
			)
		)
		(pad "S" smd custom
			(at 0.98425 0.9525)
			(size 0.1905 0.1905)
			(layers "F.Cu" "F.Mask" "F.Paste")
			(net "GND")
			(options
				(clearance outline)
				(anchor circle)
			)
			(primitives
				(gr_poly
					(pts
						(arc
							(start -0.1778 0.5715)
							(mid -0.321484 0.511984)
							(end -0.381 0.3683)
						)
						(arc
							(start -0.381 -0.3683)
							(mid -0.321484 -0.511984)
							(end -0.1778 -0.5715)
						)
						(arc
							(start 0.1778 -0.5715)
							(mid 0.321484 -0.511984)
							(end 0.381 -0.3683)
						)
						(arc
							(start 0.381 0.3683)
							(mid 0.321484 0.511984)
							(end 0.1778 0.5715)
						)
					)
					(width 0)
					(fill yes)
				)
			)
		)
	)
	(footprint ""
		(layer "F.Cu")
		(at 35.271202 -255.42875 -90)
		(property "Reference" "R1207"
			(at 0 0 270)
			(layer "F.SilkS")
			(hide yes)
			(effects
				(font
					(size 1.27 1.27)
				)
			)
		)
		(property "Value" "0R2J-2-GP"
			(at 0.064008 -3.993896 270)
			(unlocked yes)
			(layer "F.Fab")
			(hide yes)
			(effects
				(font
					(size 1.016 1.016)
					(thickness 0.1524)
				)
			)
		)
		(property "Device Type" "R402H16"
			(at 0.064008 -5.517896 270)
			(unlocked yes)
			(layer "F.Fab")
			(hide yes)
			(effects
				(font
					(size 1.016 1.016)
					(thickness 0.1524)
				)
			)
		)
		(duplicate_pad_numbers_are_jumpers no)
		(fp_line
			(start -0.508 -0.9398)
			(end -0.508 0.9398)
			(stroke
				(width 0.1524)
				(type default)
			)
			(layer "F.SilkS")
		)
		(fp_line
			(start 0.508 -0.9398)
			(end -0.508 -0.9398)
			(stroke
				(width 0.1524)
				(type default)
			)
			(layer "F.SilkS")
		)
		(fp_rect
			(start -0.508 0.9398)
			(end 0.508 -0.9398)
			(stroke
				(width 0)
				(type default)
			)
			(fill no)
			(layer "F.CrtYd")
		)
		(fp_rect
			(start -0.508 0.9398)
			(end 0.508 -0.9398)
			(stroke
				(width 0)
				(type default)
			)
			(fill no)
			(layer "F.Fab")
		)
		(pad "1" smd custom
			(at 0 -0.4445 270)
			(size 0.1397 0.1397)
			(layers "F.Cu" "F.Mask" "F.Paste")
			(net "P12V_A_PGOOD")
			(options
				(clearance outline)
				(anchor circle)
			)
			(primitives
				(gr_poly
					(pts
						(arc
							(start -0.1778 -0.2794)
							(mid -0.249642 -0.249642)
							(end -0.2794 -0.1778)
						)
						(arc
							(start -0.2794 0.1778)
							(mid -0.249642 0.249642)
							(end -0.1778 0.2794)
						)
						(arc
							(start 0.1778 0.2794)
							(mid 0.249642 0.249642)
							(end 0.2794 0.1778)
						)
						(arc
							(start 0.2794 -0.1778)
							(mid 0.249642 -0.249642)
							(end 0.1778 -0.2794)
						)
					)
					(width 0)
					(fill yes)
				)
			)
		)
		(pad "2" smd custom
			(at 0 0.4445 270)
			(size 0.1397 0.1397)
			(layers "F.Cu" "F.Mask" "F.Paste")
			(net "P5V_A_EN_R")
			(options
				(clearance outline)
				(anchor circle)
			)
			(primitives
				(gr_poly
					(pts
						(arc
							(start -0.1778 -0.2794)
							(mid -0.249642 -0.249642)
							(end -0.2794 -0.1778)
						)
						(arc
							(start -0.2794 0.1778)
							(mid -0.249642 0.249642)
							(end -0.1778 0.2794)
						)
						(arc
							(start 0.1778 0.2794)
							(mid 0.249642 0.249642)
							(end 0.2794 0.1778)
						)
						(arc
							(start 0.2794 -0.1778)
							(mid 0.249642 -0.249642)
							(end 0.1778 -0.2794)
						)
					)
					(width 0)
					(fill yes)
				)
			)
		)
	)
	(footprint ""
		(layer "F.Cu")
		(at 127.113284 -44.219368 90)
		(property "Reference" "C389"
			(at 0 0 90)
			(layer "F.SilkS")
			(hide yes)
			(effects
				(font
					(size 1.27 1.27)
				)
			)
		)
		(property "Value" "SCD01U16V1KX-GP"
			(at -2.8321 -1.7399 90)
			(unlocked yes)
			(layer "F.Fab")
			(hide yes)
			(effects
				(font
					(size 1.016 1.016)
					(thickness 0.1524)
				)
			)
		)
		(property "Device Type" "C0201H13"
			(at -2.8321 -3.2639 90)
			(unlocked yes)
			(layer "F.Fab")
			(hide yes)
			(effects
				(font
					(size 1.016 1.016)
					(thickness 0.1524)
				)
			)
		)
		(duplicate_pad_numbers_are_jumpers no)
		(fp_rect
			(start -0.2794 0.6477)
			(end 0.2794 -0.6477)
			(stroke
				(width 0)
				(type default)
			)
			(fill no)
			(layer "F.CrtYd")
		)
		(fp_rect
			(start -0.2794 0.6477)
			(end 0.2794 -0.6477)
			(stroke
				(width 0)
				(type default)
			)
			(fill no)
			(layer "F.Fab")
		)
		(pad "1" smd custom
			(at 0 -0.2794 90)
			(size 0.0762 0.0762)
			(layers "F.Cu" "F.Mask" "F.Paste")
			(net "SAS_HDD_RX_N27")
			(options
				(clearance outline)
				(anchor circle)
			)
			(primitives
				(gr_poly
					(pts
						(arc
							(start 0.1524 -0.127)
							(mid 0.137521 -0.162921)
							(end 0.1016 -0.1778)
						)
						(arc
							(start -0.1016 -0.1778)
							(mid -0.137521 -0.162921)
							(end -0.1524 -0.127)
						)
						(arc
							(start -0.1524 0.127)
							(mid -0.137521 0.162921)
							(end -0.1016 0.1778)
						)
						(arc
							(start 0.1016 0.1778)
							(mid 0.137521 0.162921)
							(end 0.1524 0.127)
						)
					)
					(width 0)
					(fill yes)
				)
			)
		)
		(pad "2" smd custom
			(at 0 0.2794 90)
			(size 0.0762 0.0762)
			(layers "F.Cu" "F.Mask" "F.Paste")
			(net "PHY_SCC_A_TO_DRV_A_27_DN")
			(options
				(clearance outline)
				(anchor circle)
			)
			(primitives
				(gr_poly
					(pts
						(arc
							(start 0.1524 -0.127)
							(mid 0.137521 -0.162921)
							(end 0.1016 -0.1778)
						)
						(arc
							(start -0.1016 -0.1778)
							(mid -0.137521 -0.162921)
							(end -0.1524 -0.127)
						)
						(arc
							(start -0.1524 0.127)
							(mid -0.137521 0.162921)
							(end -0.1016 0.1778)
						)
						(arc
							(start 0.1016 0.1778)
							(mid 0.137521 0.162921)
							(end 0.1524 0.127)
						)
					)
					(width 0)
					(fill yes)
				)
			)
		)
	)
	(footprint ""
		(layer "F.Cu")
		(at 30.14853 -253.763018 90)
		(property "Reference" "R1215"
			(at 0 0 90)
			(layer "F.SilkS")
			(hide yes)
			(effects
				(font
					(size 1.27 1.27)
				)
			)
		)
		(property "Value" "100KR2F-L1-GP"
			(at 0.064008 -3.993896 90)
			(unlocked yes)
			(layer "F.Fab")
			(hide yes)
			(effects
				(font
					(size 1.016 1.016)
					(thickness 0.1524)
				)
			)
		)
		(property "Device Type" "R402H16"
			(at 0.064008 -5.517896 90)
			(unlocked yes)
			(layer "F.Fab")
			(hide yes)
			(effects
				(font
					(size 1.016 1.016)
					(thickness 0.1524)
				)
			)
		)
		(duplicate_pad_numbers_are_jumpers no)
		(fp_line
			(start 0.508 -0.9398)
			(end -0.508 -0.9398)
			(stroke
				(width 0.1524)
				(type default)
			)
			(layer "F.SilkS")
		)
		(fp_line
			(start -0.508 -0.9398)
			(end -0.508 0.9398)
			(stroke
				(width 0.1524)
				(type default)
			)
			(layer "F.SilkS")
		)
		(fp_rect
			(start -0.508 0.9398)
			(end 0.508 -0.9398)
			(stroke
				(width 0)
				(type default)
			)
			(fill no)
			(layer "F.CrtYd")
		)
		(fp_rect
			(start -0.508 0.9398)
			(end 0.508 -0.9398)
			(stroke
				(width 0)
				(type default)
			)
			(fill no)
			(layer "F.Fab")
		)
		(pad "1" smd custom
			(at 0 -0.4445 90)
			(size 0.1397 0.1397)
			(layers "F.Cu" "F.Mask" "F.Paste")
			(net "AGND_P5V_A")
			(options
				(clearance outline)
				(anchor circle)
			)
			(primitives
				(gr_poly
					(pts
						(arc
							(start -0.1778 -0.2794)
							(mid -0.249642 -0.249642)
							(end -0.2794 -0.1778)
						)
						(arc
							(start -0.2794 0.1778)
							(mid -0.249642 0.249642)
							(end -0.1778 0.2794)
						)
						(arc
							(start 0.1778 0.2794)
							(mid 0.249642 0.249642)
							(end 0.2794 0.1778)
						)
						(arc
							(start 0.2794 -0.1778)
							(mid 0.249642 -0.249642)
							(end 0.1778 -0.2794)
						)
					)
					(width 0)
					(fill yes)
				)
			)
		)
		(pad "2" smd custom
			(at 0 0.4445 90)
			(size 0.1397 0.1397)
			(layers "F.Cu" "F.Mask" "F.Paste")
			(net "P5V_A_MODE")
			(options
				(clearance outline)
				(anchor circle)
			)
			(primitives
				(gr_poly
					(pts
						(arc
							(start -0.1778 -0.2794)
							(mid -0.249642 -0.249642)
							(end -0.2794 -0.1778)
						)
						(arc
							(start -0.2794 0.1778)
							(mid -0.249642 0.249642)
							(end -0.1778 0.2794)
						)
						(arc
							(start 0.1778 0.2794)
							(mid 0.249642 0.249642)
							(end 0.2794 0.1778)
						)
						(arc
							(start 0.2794 -0.1778)
							(mid 0.249642 -0.249642)
							(end 0.1778 -0.2794)
						)
					)
					(width 0)
					(fill yes)
				)
			)
		)
	)
	(footprint ""
		(layer "F.Cu")
		(at 190.5 -173.1772 90)
		(property "Reference" "C267"
			(at 0 0 90)
			(layer "F.SilkS")
			(hide yes)
			(effects
				(font
					(size 1.27 1.27)
				)
			)
		)
		(property "Value" "SCD01U50V2KX-1GP"
			(at 1.1811 -2.7051 90)
			(unlocked yes)
			(layer "F.Fab")
			(hide yes)
			(effects
				(font
					(size 1.016 1.016)
					(thickness 0.1524)
				)
			)
		)
		(property "Device Type" "C402H22"
			(at 1.1811 -4.2291 90)
			(unlocked yes)
			(layer "F.Fab")
			(hide yes)
			(effects
				(font
					(size 1.016 1.016)
					(thickness 0.1524)
				)
			)
		)
		(duplicate_pad_numbers_are_jumpers no)
		(fp_rect
			(start -0.4318 0.9525)
			(end 0.4318 -0.9525)
			(stroke
				(width 0)
				(type default)
			)
			(fill no)
			(layer "F.CrtYd")
		)
		(fp_rect
			(start -0.4318 0.9525)
			(end 0.4318 -0.9525)
			(stroke
				(width 0)
				(type default)
			)
			(fill no)
			(layer "F.Fab")
		)
		(pad "1" smd custom
			(at 0 -0.4445 90)
			(size 0.1524 0.1524)
			(layers "F.Cu" "F.Mask" "F.Paste")
			(net "HDD_PRSNT_17")
			(options
				(clearance outline)
				(anchor circle)
			)
			(primitives
				(gr_poly
					(pts
						(arc
							(start 0.3048 -0.2032)
							(mid 0.275042 -0.275042)
							(end 0.2032 -0.3048)
						)
						(arc
							(start -0.2032 -0.3048)
							(mid -0.275042 -0.275042)
							(end -0.3048 -0.2032)
						)
						(arc
							(start -0.3048 0.2032)
							(mid -0.275042 0.275042)
							(end -0.2032 0.3048)
						)
						(arc
							(start 0.2032 0.3048)
							(mid 0.275042 0.275042)
							(end 0.3048 0.2032)
						)
					)
					(width 0)
					(fill yes)
				)
			)
		)
		(pad "2" smd custom
			(at 0 0.4445 90)
			(size 0.1524 0.1524)
			(layers "F.Cu" "F.Mask" "F.Paste")
			(net "GND")
			(options
				(clearance outline)
				(anchor circle)
			)
			(primitives
				(gr_poly
					(pts
						(arc
							(start 0.3048 -0.2032)
							(mid 0.275042 -0.275042)
							(end 0.2032 -0.3048)
						)
						(arc
							(start -0.2032 -0.3048)
							(mid -0.275042 -0.275042)
							(end -0.3048 -0.2032)
						)
						(arc
							(start -0.3048 0.2032)
							(mid -0.275042 0.275042)
							(end -0.2032 0.3048)
						)
						(arc
							(start 0.2032 0.3048)
							(mid 0.275042 0.275042)
							(end 0.3048 0.2032)
						)
					)
					(width 0)
					(fill yes)
				)
			)
		)
	)
	(footprint ""
		(layer "F.Cu")
		(at 441.349892 -324.39991)
		(property "Reference" "RLED35"
			(at 0 0 0)
			(layer "F.SilkS")
			(hide yes)
			(effects
				(font
					(size 1.27 1.27)
				)
			)
		)
		(property "Value" "LED-BY-19-GP"
			(at -2.132076 1.414018 0)
			(unlocked yes)
			(layer "F.Fab")
			(hide yes)
			(effects
				(font
					(size 1.016 1.016)
					(thickness 0.1524)
				)
			)
		)
		(property "Device Type" "LED-1615-4PH26"
			(at -2.132076 -0.109982 0)
			(unlocked yes)
			(layer "F.Fab")
			(hide yes)
			(effects
				(font
					(size 1.016 1.016)
					(thickness 0.1524)
				)
			)
		)
		(duplicate_pad_numbers_are_jumpers no)
		(fp_line
			(start -1.2954 0.254)
			(end -1.2954 1.6002)
			(stroke
				(width 0.508)
				(type default)
			)
			(layer "F.SilkS")
		)
		(fp_line
			(start -1.2954 1.6002)
			(end 1.2954 1.6002)
			(stroke
				(width 0.508)
				(type default)
			)
			(layer "F.SilkS")
		)
		(fp_line
			(start -1.1176 -1.4224)
			(end 1.1176 -1.4224)
			(stroke
				(width 0.1524)
				(type default)
			)
			(layer "F.SilkS")
		)
		(fp_line
			(start -1.1176 1.4224)
			(end -1.1176 -1.4224)
			(stroke
				(width 0.1524)
				(type default)
			)
			(layer "F.SilkS")
		)
		(fp_line
			(start 1.1176 -1.4224)
			(end 1.1176 1.4224)
			(stroke
				(width 0.1524)
				(type default)
			)
			(layer "F.SilkS")
		)
		(fp_line
			(start 1.1176 1.4224)
			(end -1.1176 1.4224)
			(stroke
				(width 0.1524)
				(type default)
			)
			(layer "F.SilkS")
		)
		(fp_line
			(start 1.2954 1.6002)
			(end 1.2954 0.254)
			(stroke
				(width 0.508)
				(type default)
			)
			(layer "F.SilkS")
		)
		(fp_rect
			(start -0.7493 0.8001)
			(end 0.7493 -0.8001)
			(stroke
				(width 0)
				(type default)
			)
			(fill no)
			(layer "F.CrtYd")
		)
		(fp_poly
			(pts
				(xy -1.3716 1.6764) (xy -1.3716 -1.6764) (xy 1.3716 -1.6764) (xy 1.3716 0.0635) (xy 0.7493 0.0635)
				(xy 0.7493 -0.8001) (xy -0.7493 -0.8001) (xy -0.7493 0.8001) (xy 0.7493 0.8001) (xy 0.7493 0.0762)
				(xy 1.3716 0.0762) (xy 1.3716 1.6764)
			)
			(stroke
				(width 0)
				(type default)
			)
			(fill no)
			(layer "F.CrtYd")
		)
		(fp_rect
			(start -1.3716 1.6764)
			(end 1.3716 -1.6764)
			(stroke
				(width 0)
				(type default)
			)
			(fill no)
			(layer "F.Fab")
		)
		(pad "1" smd rect
			(at 0.50038 -0.73025)
			(size 0.7112 0.8636)
			(layers "F.Cu" "F.Mask" "F.Paste")
			(net "DRV_ACT_34")
		)
		(pad "2" smd rect
			(at -0.50038 -0.73025)
			(size 0.7112 0.8636)
			(layers "F.Cu" "F.Mask" "F.Paste")
			(net "FLT_HDD34")
		)
		(pad "3" smd rect
			(at 0.50038 0.73025)
			(size 0.7112 0.8636)
			(layers "F.Cu" "F.Mask" "F.Paste")
			(net "DRV_ACT_34_N")
		)
		(pad "4" smd rect
			(at -0.50038 0.73025)
			(size 0.7112 0.8636)
			(layers "F.Cu" "F.Mask" "F.Paste")
			(net "FLT_HDD34_N")
		)
	)
	(footprint ""
		(layer "F.Cu")
		(at 416.284664 -273.660616 -90)
		(property "Reference" "C156"
			(at 0 0 270)
			(layer "F.SilkS")
			(hide yes)
			(effects
				(font
					(size 1.27 1.27)
				)
			)
		)
		(property "Value" "SCD01U16V1KX-GP"
			(at -2.8321 -1.7399 270)
			(unlocked yes)
			(layer "F.Fab")
			(hide yes)
			(effects
				(font
					(size 1.016 1.016)
					(thickness 0.1524)
				)
			)
		)
		(property "Device Type" "C0201H13"
			(at -2.8321 -3.2639 270)
			(unlocked yes)
			(layer "F.Fab")
			(hide yes)
			(effects
				(font
					(size 1.016 1.016)
					(thickness 0.1524)
				)
			)
		)
		(duplicate_pad_numbers_are_jumpers no)
		(fp_rect
			(start -0.2794 0.6477)
			(end 0.2794 -0.6477)
			(stroke
				(width 0)
				(type default)
			)
			(fill no)
			(layer "F.CrtYd")
		)
		(fp_rect
			(start -0.2794 0.6477)
			(end 0.2794 -0.6477)
			(stroke
				(width 0)
				(type default)
			)
			(fill no)
			(layer "F.Fab")
		)
		(pad "1" smd custom
			(at 0 -0.2794 270)
			(size 0.0762 0.0762)
			(layers "F.Cu" "F.Mask" "F.Paste")
			(net "SAS_HDD_RX_P9")
			(options
				(clearance outline)
				(anchor circle)
			)
			(primitives
				(gr_poly
					(pts
						(arc
							(start 0.1524 -0.127)
							(mid 0.137521 -0.162921)
							(end 0.1016 -0.1778)
						)
						(arc
							(start -0.1016 -0.1778)
							(mid -0.137521 -0.162921)
							(end -0.1524 -0.127)
						)
						(arc
							(start -0.1524 0.127)
							(mid -0.137521 0.162921)
							(end -0.1016 0.1778)
						)
						(arc
							(start 0.1016 0.1778)
							(mid 0.137521 0.162921)
							(end 0.1524 0.127)
						)
					)
					(width 0)
					(fill yes)
				)
			)
		)
		(pad "2" smd custom
			(at 0 0.2794 270)
			(size 0.0762 0.0762)
			(layers "F.Cu" "F.Mask" "F.Paste")
			(net "PHY_SCC_A_TO_DRV_A_9_DP")
			(options
				(clearance outline)
				(anchor circle)
			)
			(primitives
				(gr_poly
					(pts
						(arc
							(start 0.1524 -0.127)
							(mid 0.137521 -0.162921)
							(end 0.1016 -0.1778)
						)
						(arc
							(start -0.1016 -0.1778)
							(mid -0.137521 -0.162921)
							(end -0.1524 -0.127)
						)
						(arc
							(start -0.1524 0.127)
							(mid -0.137521 0.162921)
							(end -0.1016 0.1778)
						)
						(arc
							(start 0.1016 0.1778)
							(mid 0.137521 0.162921)
							(end 0.1524 0.127)
						)
					)
					(width 0)
					(fill yes)
				)
			)
		)
	)
)
